# BASEBOARD_FAB2 (Tioga Pass) — schematic netlist excerpt (pin names and nets, part order shuffled) for the footprints in the layout excerpt that follows; sources: Cadence DE-HDL packaged netlist, KiCad conversion of Wiwynn_Tioga_Pass_MB.brd

R4D64  RES  3.16K 1% CHIP  pkg 0402  page 213 : A = VR_PVCCIO_CPU1_XADDR1 ; B = GND
C4E15  CAP  1.0UF 16V 10% X6S  pkg 0402  page 214 : A = VR_FET_SW_P12V_STBY_PVCCIN_CPU0 ; B = GND
R1D32  RES  100.0K 1% CHIP  pkg 0402  page 199 : A = A_HSC_VCAP ; B = A_HSC_ISTART

(kicad_pcb
	(version 20260206)
	(generator "pcbnew")
	(generator_version "10.0")
	(general
		(thickness 1.6)
		(legacy_teardrops no)
	)
	(paper "A4")
	(title_block
		(title "Wiwynn_Tioga_Pass_MB.brd")
		(comment 1 "Tioga Pass / footprints 1992-1994 of 4770")
	)
	(layers
		(0 "F.Cu" signal "TOP")
		(4 "In1.Cu" signal "L2GND")
		(6 "In2.Cu" signal "L3")
		(8 "In3.Cu" signal "L4GND")
		(10 "In4.Cu" signal "L5")
		(12 "In5.Cu" signal "L6GND")
		(14 "In6.Cu" signal "L7VCC")
		(16 "In7.Cu" signal "L8VCC")
		(18 "In8.Cu" signal "L9GND")
		(20 "In9.Cu" signal "L10")
		(22 "In10.Cu" signal "L11GND")
		(24 "In11.Cu" signal "L12")
		(26 "In12.Cu" signal "L13GND")
		(2 "B.Cu" signal "BOTTOM")
		(9 "F.Adhes" user "F.Adhesive")
		(11 "B.Adhes" user "B.Adhesive")
		(13 "F.Paste" user "Package Geometry/Pastemask Top")
		(15 "B.Paste" user "Package Geometry/Pastemask Bottom")
		(5 "F.SilkS" user "Ref Des/Silkscreen Top")
		(7 "B.SilkS" user "Ref Des/Silkscreen Bottom")
		(1 "F.Mask" user "Board Geometry/Soldermask Top")
		(3 "B.Mask" user "Board Geometry/Soldermask Bottom")
		(17 "Dwgs.User" user "User.Drawings")
		(19 "Cmts.User" user "User.Comments")
		(21 "Eco1.User" user "User.Eco1")
		(23 "Eco2.User" user "User.Eco2")
		(25 "Edge.Cuts" user "Board Geometry/Outline")
		(27 "Margin" user)
		(31 "F.CrtYd" user "Package Geometry/Place Bound Top")
		(29 "B.CrtYd" user "Package Geometry/Place Bound Bottom")
		(35 "F.Fab" user "Ref Des/Assembly Top")
		(33 "B.Fab" user "Ref Des/Assembly Bottom")
	)
	(footprint ""
		(layer "F.Cu")
		(at 181.483 -51.5874 90)
		(property "Reference" "C4E15"
			(at 0 0 90)
			(layer "F.SilkS")
			(hide yes)
			(effects
				(font
					(size 1.27 1.27)
				)
			)
		)
		(property "Value" ""
			(at 0 0 90)
			(layer "F.Fab")
			(effects
				(font
					(size 1.27 1.27)
				)
			)
		)
		(duplicate_pad_numbers_are_jumpers no)
		(fp_poly
			(pts
				(xy 0.3048 -0.1016) (xy 0.3048 0.9906) (xy -0.3048 0.9906) (xy -0.3048 -0.1016)
			)
			(stroke
				(width 0)
				(type default)
			)
			(fill no)
			(layer "F.CrtYd")
		)
		(fp_line
			(start 0.3048 -0.1016)
			(end -0.3048 -0.1016)
			(stroke
				(width 0.1)
				(type default)
			)
			(layer "F.Fab")
		)
		(fp_line
			(start -0.3048 -0.1016)
			(end -0.3048 0.9906)
			(stroke
				(width 0.1)
				(type default)
			)
			(layer "F.Fab")
		)
		(fp_line
			(start 0.3048 0.9906)
			(end 0.3048 -0.1016)
			(stroke
				(width 0.1)
				(type default)
			)
			(layer "F.Fab")
		)
		(fp_line
			(start -0.3048 0.9906)
			(end 0.3048 0.9906)
			(stroke
				(width 0.1)
				(type default)
			)
			(layer "F.Fab")
		)
		(pad "1" smd rect
			(at 0 0 90)
			(size 0.508 0.508)
			(layers "F.Cu" "F.Mask" "F.Paste")
			(net "VR_FET_SW_P12V_STBY_PVCCIN_CPU0")
		)
		(pad "2" smd rect
			(at 0 0.889 90)
			(size 0.508 0.508)
			(layers "F.Cu" "F.Mask" "F.Paste")
			(net "GND")
		)
		(zone
			(layer "F.Cu")
			(hatch none 0.5)
			(connect_pads
				(clearance 0)
			)
			(min_thickness 0.25)
			(keepout
				(tracks allowed)
				(vias not_allowed)
				(pads allowed)
				(copperpour not_allowed)
				(footprints allowed)
			)
			(placement
				(enabled no)
				(sheetname "")
			)
			(fill
				(thermal_gap 0.5)
				(thermal_bridge_width 0.5)
				(island_removal_mode 0)
			)
			(polygon
				(pts
					(xy 181.737 -51.3334) (xy 181.737 -51.8414) (xy 182.118 -51.8414) (xy 182.118 -51.3334)
				)
			)
		)
		(zone
			(layer "F.Cu")
			(hatch none 0.5)
			(connect_pads
				(clearance 0)
			)
			(min_thickness 0.25)
			(keepout
				(tracks not_allowed)
				(vias allowed)
				(pads allowed)
				(copperpour not_allowed)
				(footprints allowed)
			)
			(placement
				(enabled no)
				(sheetname "")
			)
			(fill
				(thermal_gap 0.5)
				(thermal_bridge_width 0.5)
				(island_removal_mode 0)
			)
			(polygon
				(pts
					(xy 182.118 -51.3334) (xy 182.118 -51.8414) (xy 181.737 -51.8414) (xy 181.737 -51.3334)
				)
			)
		)
	)
	(footprint ""
		(layer "F.Cu")
		(at 173.74108 -65.42278 90)
		(property "Reference" "R4D64"
			(at 0 0 90)
			(layer "F.SilkS")
			(hide yes)
			(effects
				(font
					(size 1.27 1.27)
				)
			)
		)
		(property "Value" ""
			(at 0 0 90)
			(layer "F.Fab")
			(effects
				(font
					(size 1.27 1.27)
				)
			)
		)
		(duplicate_pad_numbers_are_jumpers no)
		(fp_poly
			(pts
				(xy -0.2794 -0.1016) (xy 0.2794 -0.1016) (xy 0.2794 0.9906) (xy -0.2794 0.9906)
			)
			(stroke
				(width 0)
				(type default)
			)
			(fill no)
			(layer "F.CrtYd")
		)
		(fp_line
			(start 0.2794 -0.1016)
			(end -0.2794 -0.1016)
			(stroke
				(width 0.1)
				(type default)
			)
			(layer "F.Fab")
		)
		(fp_line
			(start -0.2794 -0.1016)
			(end -0.2794 0.9906)
			(stroke
				(width 0.1)
				(type default)
			)
			(layer "F.Fab")
		)
		(fp_line
			(start 0.2794 0.9906)
			(end 0.2794 -0.1016)
			(stroke
				(width 0.1)
				(type default)
			)
			(layer "F.Fab")
		)
		(fp_line
			(start -0.2794 0.9906)
			(end 0.2794 0.9906)
			(stroke
				(width 0.1)
				(type default)
			)
			(layer "F.Fab")
		)
		(pad "1" smd rect
			(at 0 0 90)
			(size 0.508 0.508)
			(layers "F.Cu" "F.Mask" "F.Paste")
			(net "VR_PVCCIO_CPU1_XADDR1")
		)
		(pad "2" smd rect
			(at 0 0.889 90)
			(size 0.508 0.508)
			(layers "F.Cu" "F.Mask" "F.Paste")
			(net "GND")
		)
		(zone
			(layer "F.Cu")
			(hatch none 0.5)
			(connect_pads
				(clearance 0)
			)
			(min_thickness 0.25)
			(keepout
				(tracks allowed)
				(vias not_allowed)
				(pads allowed)
				(copperpour not_allowed)
				(footprints allowed)
			)
			(placement
				(enabled no)
				(sheetname "")
			)
			(fill
				(thermal_gap 0.5)
				(thermal_bridge_width 0.5)
				(island_removal_mode 0)
			)
			(polygon
				(pts
					(xy 173.99508 -65.16878) (xy 173.99508 -65.67678) (xy 174.37608 -65.67678) (xy 174.37608 -65.16878)
				)
			)
		)
		(zone
			(layer "F.Cu")
			(hatch none 0.5)
			(connect_pads
				(clearance 0)
			)
			(min_thickness 0.25)
			(keepout
				(tracks not_allowed)
				(vias allowed)
				(pads allowed)
				(copperpour not_allowed)
				(footprints allowed)
			)
			(placement
				(enabled no)
				(sheetname "")
			)
			(fill
				(thermal_gap 0.5)
				(thermal_bridge_width 0.5)
				(island_removal_mode 0)
			)
			(polygon
				(pts
					(xy 174.37608 -65.16878) (xy 174.37608 -65.67678) (xy 173.99508 -65.67678) (xy 173.99508 -65.16878)
				)
			)
		)
	)
	(footprint ""
		(layer "F.Cu")
		(at 23.114 -76.327 -90)
		(property "Reference" "R1D32"
			(at 0 0 270)
			(layer "F.SilkS")
			(hide yes)
			(effects
				(font
					(size 1.27 1.27)
				)
			)
		)
		(property "Value" ""
			(at 0 0 270)
			(layer "F.Fab")
			(effects
				(font
					(size 1.27 1.27)
				)
			)
		)
		(duplicate_pad_numbers_are_jumpers no)
		(fp_poly
			(pts
				(xy -0.2794 -0.1016) (xy 0.2794 -0.1016) (xy 0.2794 0.9906) (xy -0.2794 0.9906)
			)
			(stroke
				(width 0)
				(type default)
			)
			(fill no)
			(layer "F.CrtYd")
		)
		(fp_line
			(start -0.2794 0.9906)
			(end 0.2794 0.9906)
			(stroke
				(width 0.1)
				(type default)
			)
			(layer "F.Fab")
		)
		(fp_line
			(start 0.2794 0.9906)
			(end 0.2794 -0.1016)
			(stroke
				(width 0.1)
				(type default)
			)
			(layer "F.Fab")
		)
		(fp_line
			(start -0.2794 -0.1016)
			(end -0.2794 0.9906)
			(stroke
				(width 0.1)
				(type default)
			)
			(layer "F.Fab")
		)
		(fp_line
			(start 0.2794 -0.1016)
			(end -0.2794 -0.1016)
			(stroke
				(width 0.1)
				(type default)
			)
			(layer "F.Fab")
		)
		(pad "1" smd rect
			(at 0 0 270)
			(size 0.508 0.508)
			(layers "F.Cu" "F.Mask" "F.Paste")
			(net "A_HSC_VCAP")
		)
		(pad "2" smd rect
			(at 0 0.889 270)
			(size 0.508 0.508)
			(layers "F.Cu" "F.Mask" "F.Paste")
			(net "A_HSC_ISTART")
		)
		(zone
			(layer "F.Cu")
			(hatch none 0.5)
			(connect_pads
				(clearance 0)
			)
			(min_thickness 0.25)
			(keepout
				(tracks not_allowed)
				(vias allowed)
				(pads allowed)
				(copperpour not_allowed)
				(footprints allowed)
			)
			(placement
				(enabled no)
				(sheetname "")
			)
			(fill
				(thermal_gap 0.5)
				(thermal_bridge_width 0.5)
				(island_removal_mode 0)
			)
			(polygon
				(pts
					(xy 22.479 -76.581) (xy 22.479 -76.073) (xy 22.86 -76.073) (xy 22.86 -76.581)
				)
			)
		)
		(zone
			(layer "F.Cu")
			(hatch none 0.5)
			(connect_pads
				(clearance 0)
			)
			(min_thickness 0.25)
			(keepout
				(tracks allowed)
				(vias not_allowed)
				(pads allowed)
				(copperpour not_allowed)
				(footprints allowed)
			)
			(placement
				(enabled no)
				(sheetname "")
			)
			(fill
				(thermal_gap 0.5)
				(thermal_bridge_width 0.5)
				(island_removal_mode 0)
			)
			(polygon
				(pts
					(xy 22.86 -76.581) (xy 22.86 -76.073) (xy 22.479 -76.073) (xy 22.479 -76.581)
				)
			)
		)
	)
)
